FILE_TYPE = CONNECTIVITY;
{Allegro Design Entry HDL 17.2-2016 S081 (4005846) 1/11/2022}
"PAGE_NUMBER" = 225;
0"NC";
1"P3V3\g";
2"P3V3_AUX\g";
3"P3V3\g";
4"GND\g";
5"GND\g";
6"GND\g";
7"SMB_HOST_CLK_BUF_ISO_3V3AUX_SDA_R"CDS_PHYS_NET_NAME"SMB_OCP_SFF_3V3AUX_BUF_SDA";
8"SMB_HOST_CLK_BUF_ISO_3V3AUX_SCL_R"CDS_PHYS_NET_NAME"SMB_OCP_SFF_3V3AUX_BUF_SCL";
9"PU_CLK_BUF_ISO_EN"$PHYS_NET_NAME"RST_PCIE_M2_N"CDS_PHYS_NET_NAME"HP_LVC3_OCP_V3_1_R_EN";
10"SMB_HOST_CLK_BUF_ISO_3V3AUX_SDA"CDS_PHYS_NET_NAME"SMB_OCP_SFF_3V3AUX_BUF_SDA";
11"SMB_HOST_CLK_BUF_ISO_3V3AUX_SCL"CDS_PHYS_NET_NAME"SMB_OCP_SFF_3V3AUX_BUF_SCL";
12"SMB_HOST_DB2000_3V3AUX_SDA";
13"SMB_HOST_CLK_BUF_3V3AUX_SDA";
14"SMB_HOST_CLK_BUF_3V3AUX_SCL";
15"SMB_HOST_CLK_BUF_ISO_3V3AUX_SCL"CDS_PHYS_NET_NAME"SMB_OCP_SFF_3V3AUX_BUF_SCL";
16"SMB_HOST_CLK_BUF_ISO_3V3AUX_SDA"CDS_PHYS_NET_NAME"SMB_OCP_SFF_3V3AUX_BUF_SDA";
17"SMB_HOST_9ZXL045_3V3AUX_SCL";
18"SMB_HOST_DB2000_3V3AUX_SCL";
19"SMB_HOST_9ZXL045_3V3AUX_SDA";
%"Q_RES"
"2","(1700,1025)","0","pure_quanta","I11";
;
PART_NUMBER"CS24702JB10"
TOLERANCE"5%"
VALUE"4.7K"
WATTAGE"1/16W"
MATERIAL"CHIP"
PACK_TYPE"0402LF"
$LOCATION"R4498"
CDS_LIB"pure_quanta"
CDS_LOCATION"R4498"
$SEC"1"
CDS_SEC"1";
"A"
$PN"1"3;
"B"
$PN"2"8;
%"Q_RES"
"2","(1950,1025)","0","pure_quanta","I12";
;
PART_NUMBER"CS24702JB10"
VALUE"4.7K"
PACK_TYPE"0402LF"
TOLERANCE"5%"
WATTAGE"1/16W"
MATERIAL"CHIP"
$LOCATION"R4499"
CDS_LIB"pure_quanta"
CDS_LOCATION"R4499"
$SEC"1"
CDS_SEC"1";
"A"
$PN"1"3;
"B"
$PN"2"7;
%"UNIVERSAL_POWER"
"1","(1425,1325)","0","logical_power","I13";
;
HDL_POWER"P3V3"
CDS_LIB"logical_power";
"A"3;
%"PCA9617ADP"
"1","(-25,625)","0","pure_quanta","I17";
;
PART_NUMBER"AL009617K02"
PART_TYPE"SMLF"
MATERIAL"IC"
VALUE"PCA9617ADP"
$LOCATION"U315"
CDS_LIB"pure_quanta"
CDS_LMAN_SYM_OUTLINE"-275,300,275,-300"
NEEDS_NO_SIZE"TRUE"
CDS_LOCATION"U315"
$SEC"1"
CDS_SEC"1";
"GND"
$PN"4"6;
"SCLB"
$PN"7"8;
"SDAB"
$PN"6"7;
"SDAA"
$PN"3"13;
"SCLA"
$PN"2"14;
"VCCB"
$PN"8"1;
"VCCA"
$PN"1"2;
"EN"
$PN"5"9;
%"Q_RES"
"1","(1525,-1525)","0","pure_quanta","I24";
;
PART_NUMBER"CS03322FB03"
MATERIAL"CHIP"
VALUE"33.2"
TOLERANCE"1%"
$LOCATION"R4480"
PACK_TYPE"0402LF"
WATTAGE"1/16W"
CDS_LIB"pure_quanta"
CDS_LOCATION"R4480"
$SEC"1"
CDS_SEC"1";
"B"
$PN"2"17;
"A"
$PN"1"15;
%"Q_RES"
"1","(1525,-1575)","0","pure_quanta","I25";
;
PART_NUMBER"CS03322FB03"
PACK_TYPE"0402LF"
MATERIAL"CHIP"
WATTAGE"1/16W"
VALUE"33.2"
TOLERANCE"1%"
$LOCATION"R4481"
CDS_LIB"pure_quanta"
CDS_LOCATION"R4481"
$SEC"1"
CDS_SEC"1";
"B"
$PN"2"19;
"A"
$PN"1"16;
%"Q_RES"
"1","(1550,-1025)","0","pure_quanta","I26";
;
PART_NUMBER"CS03322FB03"
TOLERANCE"1%"
VALUE"33.2"
MATERIAL"CHIP"
WATTAGE"1/16W"
PACK_TYPE"0402LF"
$LOCATION"R4497"
CDS_LIB"pure_quanta"
CDS_LOCATION"R4497"
$SEC"1"
CDS_SEC"1";
"B"
$PN"2"12;
"A"
$PN"1"16;
%"Q_RES"
"1","(1550,-975)","0","pure_quanta","I27";
;
PART_NUMBER"CS03322FB03"
TOLERANCE"1%"
VALUE"33.2"
MATERIAL"CHIP"
$LOCATION"R4496"
CDS_LIB"pure_quanta"
WATTAGE"1/16W"
PACK_TYPE"0402LF"
CDS_LOCATION"R4496"
$SEC"1"
CDS_SEC"1";
"B"
$PN"2"18;
"A"
$PN"1"15;
%"UNIVERSAL_GND"
"1","(-550,200)","0","logical_power","I3";
;
HDL_POWER"GND"
CDS_LIB"logical_power";
"A"6;
%"Q_RES"
"2","(1425,1050)","0","pure_quanta","I32";
;
PART_NUMBER"CS31002FB08"
WATTAGE"1/16W"
TOLERANCE"1%"
VALUE"10K"
MATERIAL"EMPTY"
PACK_TYPE"0402LF"
$LOCATION"R4500"
CDS_LIB"pure_quanta"
CDS_LOCATION"R4500"
$SEC"1"
CDS_SEC"1";
"A"
$PN"1"3;
"B"
$PN"2"9;
%"Q_RES"
"1","(2200,675)","0","pure_quanta","I33";
;
PART_NUMBER"CS03322FB03"
MATERIAL"CHIP"
TOLERANCE"1%"
VALUE"33.2"
$LOCATION"R4540"
WATTAGE"1/16W"
PACK_TYPE"0402LF"
CDS_LIB"pure_quanta"
CDS_LOCATION"R4540"
$SEC"1"
CDS_SEC"1";
"B"
$PN"2"11;
"A"
$PN"1"8;
%"Q_RES"
"1","(2200,575)","0","pure_quanta","I34";
;
PART_NUMBER"CS03322FB03"
PACK_TYPE"0402LF"
TOLERANCE"1%"
MATERIAL"CHIP"
VALUE"33.2"
WATTAGE"1/16W"
$LOCATION"R4541"
CDS_LIB"pure_quanta"
CDS_LOCATION"R4541"
$SEC"1"
CDS_SEC"1";
"B"
$PN"2"10;
"A"
$PN"1"7;
%"UNIVERSAL_GND"
"1","(-950,850)","0","logical_power","I4";
;
HDL_POWER"GND"
CDS_LIB"logical_power";
"A"5;
%"Q_CAP"
"1","(-950,1075)","0","pure_quanta","I5";
;
PART_NUMBER"CH4104K1B00"
VALUE"0.1UF"
VOLTAGE"25V"
TOLERANCE"10%"
MATERIAL"X7R"
PACK_TYPE"0402"
$LOCATION"C2337"
CDS_LIB"pure_quanta"
CDS_LOCATION"C2337"
$SEC"1"
CDS_SEC"1";
"B"
$PN"2"5;
"A"
$PN"1"2;
%"UNIVERSAL_POWER"
"1","(-600,1375)","0","logical_power","I6";
;
HDL_POWER"P3V3_AUX"
CDS_LIB"logical_power";
"A"2;
%"UNIVERSAL_GND"
"1","(725,875)","0","logical_power","I7";
;
CDS_LIB"logical_power"
HDL_POWER"GND";
"A"4;
%"Q_CAP"
"1","(725,1075)","0","pure_quanta","I8";
;
PART_NUMBER"CH4104K1B00"
PACK_TYPE"0402"
VOLTAGE"25V"
VALUE"0.1UF"
MATERIAL"X7R"
TOLERANCE"10%"
$LOCATION"C2338"
CDS_LIB"pure_quanta"
CDS_LOCATION"C2338"
$SEC"1"
CDS_SEC"1";
"B"
$PN"2"4;
"A"
$PN"1"1;
%"UNIVERSAL_POWER"
"1","(525,1375)","0","logical_power","I9";
;
HDL_POWER"P3V3"
CDS_LIB"logical_power";
"A"1;
END.
